(kicad_pcb
	(version 20260206)
	(generator "pcbnew")
	(generator_version "10.0")
	(general
		(thickness 1.6)
		(legacy_teardrops no)
	)
	(paper "A4")
	(title_block
		(title "Bryce Canyon_R.DPB_16317-1_OCP.brd")
		(comment 1 "Bryce Canyon / footprints 933-939 of 2099")
	)
	(layers
		(0 "F.Cu" signal "TOP")
		(4 "In1.Cu" signal "L2GND")
		(6 "In2.Cu" signal "L3")
		(8 "In3.Cu" signal "L4VCC")
		(10 "In4.Cu" signal "L5VCC")
		(12 "In5.Cu" signal "L6")
		(14 "In6.Cu" signal "L7GND")
		(2 "B.Cu" signal "BOTTOM")
		(9 "F.Adhes" user "F.Adhesive")
		(11 "B.Adhes" user "B.Adhesive")
		(13 "F.Paste" user "Package Geometry/Pastemask Top")
		(15 "B.Paste" user "Package Geometry/Pastemask Bottom")
		(5 "F.SilkS" user "Ref Des/Silkscreen Top")
		(7 "B.SilkS" user "Ref Des/Silkscreen Bottom")
		(1 "F.Mask" user "Board Geometry/Soldermask Top")
		(3 "B.Mask" user "Board Geometry/Soldermask Bottom")
		(17 "Dwgs.User" user "User.Drawings")
		(19 "Cmts.User" user "User.Comments")
		(21 "Eco1.User" user "User.Eco1")
		(23 "Eco2.User" user "User.Eco2")
		(25 "Edge.Cuts" user "Board Geometry/Outline")
		(27 "Margin" user)
		(31 "F.CrtYd" user "Package Geometry/Place Bound Top")
		(29 "B.CrtYd" user "Package Geometry/Place Bound Bottom")
		(35 "F.Fab" user "Ref Des/Assembly Top")
		(33 "B.Fab" user "Ref Des/Assembly Bottom")
	)
	(footprint ""
		(layer "F.Cu")
		(at 141.097 -254.508 -90)
		(property "Reference" "R233"
			(at 0 0 270)
			(layer "F.SilkS")
			(hide yes)
			(effects
				(font
					(size 1.27 1.27)
				)
			)
		)
		(property "Value" "300KR2F-GP"
			(at 0.064008 -3.993896 270)
			(unlocked yes)
			(layer "F.Fab")
			(hide yes)
			(effects
				(font
					(size 1.016 1.016)
					(thickness 0.1524)
				)
			)
		)
		(property "Device Type" "R402H16"
			(at 0.064008 -5.517896 270)
			(unlocked yes)
			(layer "F.Fab")
			(hide yes)
			(effects
				(font
					(size 1.016 1.016)
					(thickness 0.1524)
				)
			)
		)
		(duplicate_pad_numbers_are_jumpers no)
		(fp_line
			(start -0.508 -0.9398)
			(end -0.508 0.9398)
			(stroke
				(width 0.1524)
				(type default)
			)
			(layer "F.SilkS")
		)
		(fp_line
			(start 0.508 -0.9398)
			(end -0.508 -0.9398)
			(stroke
				(width 0.1524)
				(type default)
			)
			(layer "F.SilkS")
		)
		(fp_rect
			(start -0.508 0.9398)
			(end 0.508 -0.9398)
			(stroke
				(width 0)
				(type default)
			)
			(fill no)
			(layer "F.CrtYd")
		)
		(fp_rect
			(start -0.508 0.9398)
			(end 0.508 -0.9398)
			(stroke
				(width 0)
				(type default)
			)
			(fill no)
			(layer "F.Fab")
		)
		(pad "1" smd custom
			(at 0 -0.4445 270)
			(size 0.1397 0.1397)
			(layers "F.Cu" "F.Mask" "F.Paste")
			(net "SW_HDD_N4")
			(options
				(clearance outline)
				(anchor circle)
			)
			(primitives
				(gr_poly
					(pts
						(arc
							(start -0.1778 -0.2794)
							(mid -0.249642 -0.249642)
							(end -0.2794 -0.1778)
						)
						(arc
							(start -0.2794 0.1778)
							(mid -0.249642 0.249642)
							(end -0.1778 0.2794)
						)
						(arc
							(start 0.1778 0.2794)
							(mid 0.249642 0.249642)
							(end 0.2794 0.1778)
						)
						(arc
							(start 0.2794 -0.1778)
							(mid 0.249642 -0.249642)
							(end 0.1778 -0.2794)
						)
					)
					(width 0)
					(fill yes)
				)
			)
		)
		(pad "2" smd custom
			(at 0 0.4445 270)
			(size 0.1397 0.1397)
			(layers "F.Cu" "F.Mask" "F.Paste")
			(net "P12V_B")
			(options
				(clearance outline)
				(anchor circle)
			)
			(primitives
				(gr_poly
					(pts
						(arc
							(start -0.1778 -0.2794)
							(mid -0.249642 -0.249642)
							(end -0.2794 -0.1778)
						)
						(arc
							(start -0.2794 0.1778)
							(mid -0.249642 0.249642)
							(end -0.1778 0.2794)
						)
						(arc
							(start 0.1778 0.2794)
							(mid 0.249642 0.249642)
							(end 0.2794 0.1778)
						)
						(arc
							(start 0.2794 -0.1778)
							(mid 0.249642 -0.249642)
							(end 0.1778 -0.2794)
						)
					)
					(width 0)
					(fill yes)
				)
			)
		)
	)
	(footprint ""
		(layer "F.Cu")
		(at 236.601 -223.52 90)
		(property "Reference" "C13"
			(at 0 0 90)
			(layer "F.SilkS")
			(hide yes)
			(effects
				(font
					(size 1.27 1.27)
				)
			)
		)
		(property "Value" "SC1U16V3KX-5GP"
			(at 0 -2.8194 90)
			(unlocked yes)
			(layer "F.Fab")
			(hide yes)
			(effects
				(font
					(size 1.016 1.016)
					(thickness 0.1524)
				)
			)
		)
		(property "Device Type" "C603H36"
			(at 0 -4.3434 90)
			(unlocked yes)
			(layer "F.Fab")
			(hide yes)
			(effects
				(font
					(size 1.016 1.016)
					(thickness 0.1524)
				)
			)
		)
		(duplicate_pad_numbers_are_jumpers no)
		(fp_line
			(start 0.508 0)
			(end -0.508 0)
			(stroke
				(width 0.2032)
				(type default)
			)
			(layer "F.SilkS")
		)
		(fp_rect
			(start -0.5842 1.3335)
			(end 0.5842 -1.3335)
			(stroke
				(width 0)
				(type default)
			)
			(fill no)
			(layer "F.CrtYd")
		)
		(fp_rect
			(start -0.5842 1.3335)
			(end 0.5842 -1.3335)
			(stroke
				(width 0)
				(type default)
			)
			(fill no)
			(layer "F.Fab")
		)
		(pad "1" smd custom
			(at 0 -0.762 90)
			(size 0.2159 0.2159)
			(layers "F.Cu" "F.Mask" "F.Paste")
			(net "GPIO_VCC_U8")
			(options
				(clearance outline)
				(anchor circle)
			)
			(primitives
				(gr_poly
					(pts
						(arc
							(start -0.3302 -0.4318)
							(mid -0.402042 -0.402042)
							(end -0.4318 -0.3302)
						)
						(arc
							(start -0.4318 0.3302)
							(mid -0.402042 0.402042)
							(end -0.3302 0.4318)
						)
						(arc
							(start 0.3302 0.4318)
							(mid 0.402042 0.402042)
							(end 0.4318 0.3302)
						)
						(arc
							(start 0.4318 -0.3302)
							(mid 0.402042 -0.402042)
							(end 0.3302 -0.4318)
						)
					)
					(width 0)
					(fill yes)
				)
			)
		)
		(pad "2" smd custom
			(at 0 0.762 90)
			(size 0.2159 0.2159)
			(layers "F.Cu" "F.Mask" "F.Paste")
			(net "GND")
			(options
				(clearance outline)
				(anchor circle)
			)
			(primitives
				(gr_poly
					(pts
						(arc
							(start -0.3302 -0.4318)
							(mid -0.402042 -0.402042)
							(end -0.4318 -0.3302)
						)
						(arc
							(start -0.4318 0.3302)
							(mid -0.402042 0.402042)
							(end -0.3302 0.4318)
						)
						(arc
							(start 0.3302 0.4318)
							(mid 0.402042 0.402042)
							(end 0.4318 0.3302)
						)
						(arc
							(start 0.4318 -0.3302)
							(mid 0.402042 -0.402042)
							(end 0.3302 -0.4318)
						)
					)
					(width 0)
					(fill yes)
				)
			)
		)
	)
	(footprint ""
		(layer "F.Cu")
		(at 470.281 -133.858 -90)
		(property "Reference" "R616"
			(at 0 0 270)
			(layer "F.SilkS")
			(hide yes)
			(effects
				(font
					(size 1.27 1.27)
				)
			)
		)
		(property "Value" "0R2J-2-GP"
			(at 0.064008 -3.993896 270)
			(unlocked yes)
			(layer "F.Fab")
			(hide yes)
			(effects
				(font
					(size 1.016 1.016)
					(thickness 0.1524)
				)
			)
		)
		(property "Device Type" "R402H16"
			(at 0.064008 -5.517896 270)
			(unlocked yes)
			(layer "F.Fab")
			(hide yes)
			(effects
				(font
					(size 1.016 1.016)
					(thickness 0.1524)
				)
			)
		)
		(duplicate_pad_numbers_are_jumpers no)
		(fp_line
			(start -0.508 -0.9398)
			(end -0.508 0.9398)
			(stroke
				(width 0.1524)
				(type default)
			)
			(layer "F.SilkS")
		)
		(fp_line
			(start 0.508 -0.9398)
			(end -0.508 -0.9398)
			(stroke
				(width 0.1524)
				(type default)
			)
			(layer "F.SilkS")
		)
		(fp_rect
			(start -0.508 0.9398)
			(end 0.508 -0.9398)
			(stroke
				(width 0)
				(type default)
			)
			(fill no)
			(layer "F.CrtYd")
		)
		(fp_rect
			(start -0.508 0.9398)
			(end 0.508 -0.9398)
			(stroke
				(width 0)
				(type default)
			)
			(fill no)
			(layer "F.Fab")
		)
		(pad "1" smd custom
			(at 0 -0.4445 270)
			(size 0.1397 0.1397)
			(layers "F.Cu" "F.Mask" "F.Paste")
			(net "SW_HDD_G23")
			(options
				(clearance outline)
				(anchor circle)
			)
			(primitives
				(gr_poly
					(pts
						(arc
							(start -0.1778 -0.2794)
							(mid -0.249642 -0.249642)
							(end -0.2794 -0.1778)
						)
						(arc
							(start -0.2794 0.1778)
							(mid -0.249642 0.249642)
							(end -0.1778 0.2794)
						)
						(arc
							(start 0.1778 0.2794)
							(mid 0.249642 0.249642)
							(end 0.2794 0.1778)
						)
						(arc
							(start 0.2794 -0.1778)
							(mid 0.249642 -0.249642)
							(end 0.1778 -0.2794)
						)
					)
					(width 0)
					(fill yes)
				)
			)
		)
		(pad "2" smd custom
			(at 0 0.4445 270)
			(size 0.1397 0.1397)
			(layers "F.Cu" "F.Mask" "F.Paste")
			(net "SW_HDD_R23")
			(options
				(clearance outline)
				(anchor circle)
			)
			(primitives
				(gr_poly
					(pts
						(arc
							(start -0.1778 -0.2794)
							(mid -0.249642 -0.249642)
							(end -0.2794 -0.1778)
						)
						(arc
							(start -0.2794 0.1778)
							(mid -0.249642 0.249642)
							(end -0.1778 0.2794)
						)
						(arc
							(start 0.1778 0.2794)
							(mid 0.249642 0.249642)
							(end 0.2794 0.1778)
						)
						(arc
							(start 0.2794 -0.1778)
							(mid 0.249642 -0.249642)
							(end 0.1778 -0.2794)
						)
					)
					(width 0)
					(fill yes)
				)
			)
		)
	)
	(footprint ""
		(layer "F.Cu")
		(at 172.593 -254.508 -90)
		(property "Reference" "R249"
			(at 0 0 270)
			(layer "F.SilkS")
			(hide yes)
			(effects
				(font
					(size 1.27 1.27)
				)
			)
		)
		(property "Value" "300KR2F-GP"
			(at 0.064008 -3.993896 270)
			(unlocked yes)
			(layer "F.Fab")
			(hide yes)
			(effects
				(font
					(size 1.016 1.016)
					(thickness 0.1524)
				)
			)
		)
		(property "Device Type" "R402H16"
			(at 0.064008 -5.517896 270)
			(unlocked yes)
			(layer "F.Fab")
			(hide yes)
			(effects
				(font
					(size 1.016 1.016)
					(thickness 0.1524)
				)
			)
		)
		(duplicate_pad_numbers_are_jumpers no)
		(fp_line
			(start -0.508 -0.9398)
			(end -0.508 0.9398)
			(stroke
				(width 0.1524)
				(type default)
			)
			(layer "F.SilkS")
		)
		(fp_line
			(start 0.508 -0.9398)
			(end -0.508 -0.9398)
			(stroke
				(width 0.1524)
				(type default)
			)
			(layer "F.SilkS")
		)
		(fp_rect
			(start -0.508 0.9398)
			(end 0.508 -0.9398)
			(stroke
				(width 0)
				(type default)
			)
			(fill no)
			(layer "F.CrtYd")
		)
		(fp_rect
			(start -0.508 0.9398)
			(end 0.508 -0.9398)
			(stroke
				(width 0)
				(type default)
			)
			(fill no)
			(layer "F.Fab")
		)
		(pad "1" smd custom
			(at 0 -0.4445 270)
			(size 0.1397 0.1397)
			(layers "F.Cu" "F.Mask" "F.Paste")
			(net "SW_HDD_N5")
			(options
				(clearance outline)
				(anchor circle)
			)
			(primitives
				(gr_poly
					(pts
						(arc
							(start -0.1778 -0.2794)
							(mid -0.249642 -0.249642)
							(end -0.2794 -0.1778)
						)
						(arc
							(start -0.2794 0.1778)
							(mid -0.249642 0.249642)
							(end -0.1778 0.2794)
						)
						(arc
							(start 0.1778 0.2794)
							(mid 0.249642 0.249642)
							(end 0.2794 0.1778)
						)
						(arc
							(start 0.2794 -0.1778)
							(mid 0.249642 -0.249642)
							(end 0.1778 -0.2794)
						)
					)
					(width 0)
					(fill yes)
				)
			)
		)
		(pad "2" smd custom
			(at 0 0.4445 270)
			(size 0.1397 0.1397)
			(layers "F.Cu" "F.Mask" "F.Paste")
			(net "P12V_B")
			(options
				(clearance outline)
				(anchor circle)
			)
			(primitives
				(gr_poly
					(pts
						(arc
							(start -0.1778 -0.2794)
							(mid -0.249642 -0.249642)
							(end -0.2794 -0.1778)
						)
						(arc
							(start -0.2794 0.1778)
							(mid -0.249642 0.249642)
							(end -0.1778 0.2794)
						)
						(arc
							(start 0.1778 0.2794)
							(mid 0.249642 0.249642)
							(end 0.2794 0.1778)
						)
						(arc
							(start 0.2794 -0.1778)
							(mid 0.249642 -0.249642)
							(end 0.1778 -0.2794)
						)
					)
					(width 0)
					(fill yes)
				)
			)
		)
	)
	(footprint ""
		(layer "F.Cu")
		(at 178.816 -19.177 180)
		(property "Reference" "R750"
			(at 0 0 180)
			(layer "F.SilkS")
			(hide yes)
			(effects
				(font
					(size 1.27 1.27)
				)
			)
		)
		(property "Value" "4K7R2F-GP"
			(at 0.064008 -3.993896 180)
			(unlocked yes)
			(layer "F.Fab")
			(hide yes)
			(effects
				(font
					(size 1.016 1.016)
					(thickness 0.1524)
				)
			)
		)
		(property "Device Type" "R402H16"
			(at 0.064008 -5.517896 180)
			(unlocked yes)
			(layer "F.Fab")
			(hide yes)
			(effects
				(font
					(size 1.016 1.016)
					(thickness 0.1524)
				)
			)
		)
		(duplicate_pad_numbers_are_jumpers no)
		(fp_line
			(start 0.508 -0.9398)
			(end -0.508 -0.9398)
			(stroke
				(width 0.1524)
				(type default)
			)
			(layer "F.SilkS")
		)
		(fp_line
			(start -0.508 -0.9398)
			(end -0.508 0.9398)
			(stroke
				(width 0.1524)
				(type default)
			)
			(layer "F.SilkS")
		)
		(fp_rect
			(start -0.508 0.9398)
			(end 0.508 -0.9398)
			(stroke
				(width 0)
				(type default)
			)
			(fill no)
			(layer "F.CrtYd")
		)
		(fp_rect
			(start -0.508 0.9398)
			(end 0.508 -0.9398)
			(stroke
				(width 0)
				(type default)
			)
			(fill no)
			(layer "F.Fab")
		)
		(pad "1" smd custom
			(at 0 -0.4445 180)
			(size 0.1397 0.1397)
			(layers "F.Cu" "F.Mask" "F.Paste")
			(net "SW_PWR_R_HDD29")
			(options
				(clearance outline)
				(anchor circle)
			)
			(primitives
				(gr_poly
					(pts
						(arc
							(start -0.1778 -0.2794)
							(mid -0.249642 -0.249642)
							(end -0.2794 -0.1778)
						)
						(arc
							(start -0.2794 0.1778)
							(mid -0.249642 0.249642)
							(end -0.1778 0.2794)
						)
						(arc
							(start 0.1778 0.2794)
							(mid 0.249642 0.249642)
							(end 0.2794 0.1778)
						)
						(arc
							(start 0.2794 -0.1778)
							(mid 0.249642 -0.249642)
							(end 0.1778 -0.2794)
						)
					)
					(width 0)
					(fill yes)
				)
			)
		)
		(pad "2" smd custom
			(at 0 0.4445 180)
			(size 0.1397 0.1397)
			(layers "F.Cu" "F.Mask" "F.Paste")
			(net "GND")
			(options
				(clearance outline)
				(anchor circle)
			)
			(primitives
				(gr_poly
					(pts
						(arc
							(start -0.1778 -0.2794)
							(mid -0.249642 -0.249642)
							(end -0.2794 -0.1778)
						)
						(arc
							(start -0.2794 0.1778)
							(mid -0.249642 0.249642)
							(end -0.1778 0.2794)
						)
						(arc
							(start 0.1778 0.2794)
							(mid 0.249642 0.249642)
							(end 0.2794 0.1778)
						)
						(arc
							(start 0.2794 -0.1778)
							(mid 0.249642 -0.249642)
							(end 0.1778 -0.2794)
						)
					)
					(width 0)
					(fill yes)
				)
			)
		)
	)
	(footprint ""
		(layer "F.Cu")
		(at 338.709 -142.875 -90)
		(property "Reference" "R499"
			(at 0 0 270)
			(layer "F.SilkS")
			(hide yes)
			(effects
				(font
					(size 1.27 1.27)
				)
			)
		)
		(property "Value" "300KR2F-GP"
			(at 0.064008 -3.993896 270)
			(unlocked yes)
			(layer "F.Fab")
			(hide yes)
			(effects
				(font
					(size 1.016 1.016)
					(thickness 0.1524)
				)
			)
		)
		(property "Device Type" "R402H16"
			(at 0.064008 -5.517896 270)
			(unlocked yes)
			(layer "F.Fab")
			(hide yes)
			(effects
				(font
					(size 1.016 1.016)
					(thickness 0.1524)
				)
			)
		)
		(duplicate_pad_numbers_are_jumpers no)
		(fp_line
			(start -0.508 -0.9398)
			(end -0.508 0.9398)
			(stroke
				(width 0.1524)
				(type default)
			)
			(layer "F.SilkS")
		)
		(fp_line
			(start 0.508 -0.9398)
			(end -0.508 -0.9398)
			(stroke
				(width 0.1524)
				(type default)
			)
			(layer "F.SilkS")
		)
		(fp_rect
			(start -0.508 0.9398)
			(end 0.508 -0.9398)
			(stroke
				(width 0)
				(type default)
			)
			(fill no)
			(layer "F.CrtYd")
		)
		(fp_rect
			(start -0.508 0.9398)
			(end 0.508 -0.9398)
			(stroke
				(width 0)
				(type default)
			)
			(fill no)
			(layer "F.Fab")
		)
		(pad "1" smd custom
			(at 0 -0.4445 270)
			(size 0.1397 0.1397)
			(layers "F.Cu" "F.Mask" "F.Paste")
			(net "SW_HDD_N18")
			(options
				(clearance outline)
				(anchor circle)
			)
			(primitives
				(gr_poly
					(pts
						(arc
							(start -0.1778 -0.2794)
							(mid -0.249642 -0.249642)
							(end -0.2794 -0.1778)
						)
						(arc
							(start -0.2794 0.1778)
							(mid -0.249642 0.249642)
							(end -0.1778 0.2794)
						)
						(arc
							(start 0.1778 0.2794)
							(mid 0.249642 0.249642)
							(end 0.2794 0.1778)
						)
						(arc
							(start 0.2794 -0.1778)
							(mid 0.249642 -0.249642)
							(end 0.1778 -0.2794)
						)
					)
					(width 0)
					(fill yes)
				)
			)
		)
		(pad "2" smd custom
			(at 0 0.4445 270)
			(size 0.1397 0.1397)
			(layers "F.Cu" "F.Mask" "F.Paste")
			(net "P12V_B")
			(options
				(clearance outline)
				(anchor circle)
			)
			(primitives
				(gr_poly
					(pts
						(arc
							(start -0.1778 -0.2794)
							(mid -0.249642 -0.249642)
							(end -0.2794 -0.1778)
						)
						(arc
							(start -0.2794 0.1778)
							(mid -0.249642 0.249642)
							(end -0.1778 0.2794)
						)
						(arc
							(start 0.1778 0.2794)
							(mid 0.249642 0.249642)
							(end 0.2794 0.1778)
						)
						(arc
							(start 0.2794 -0.1778)
							(mid 0.249642 -0.249642)
							(end 0.1778 -0.2794)
						)
					)
					(width 0)
					(fill yes)
				)
			)
		)
	)
	(footprint ""
		(layer "F.Cu")
		(at 399.288 -13.335 180)
		(property "Reference" "R819"
			(at 0 0 180)
			(layer "F.SilkS")
			(hide yes)
			(effects
				(font
					(size 1.27 1.27)
				)
			)
		)
		(property "Value" "4K7R2J-2-GP"
			(at 0.064008 -3.993896 180)
			(unlocked yes)
			(layer "F.Fab")
			(hide yes)
			(effects
				(font
					(size 1.016 1.016)
					(thickness 0.1524)
				)
			)
		)
		(property "Device Type" "R402H16"
			(at 0.064008 -5.517896 180)
			(unlocked yes)
			(layer "F.Fab")
			(hide yes)
			(effects
				(font
					(size 1.016 1.016)
					(thickness 0.1524)
				)
			)
		)
		(duplicate_pad_numbers_are_jumpers no)
		(fp_line
			(start 0.508 -0.9398)
			(end -0.508 -0.9398)
			(stroke
				(width 0.1524)
				(type default)
			)
			(layer "F.SilkS")
		)
		(fp_line
			(start -0.508 -0.9398)
			(end -0.508 0.9398)
			(stroke
				(width 0.1524)
				(type default)
			)
			(layer "F.SilkS")
		)
		(fp_rect
			(start -0.508 0.9398)
			(end 0.508 -0.9398)
			(stroke
				(width 0)
				(type default)
			)
			(fill no)
			(layer "F.CrtYd")
		)
		(fp_rect
			(start -0.508 0.9398)
			(end 0.508 -0.9398)
			(stroke
				(width 0)
				(type default)
			)
			(fill no)
			(layer "F.Fab")
		)
		(pad "1" smd custom
			(at 0 -0.4445 180)
			(size 0.1397 0.1397)
			(layers "F.Cu" "F.Mask" "F.Paste")
			(net "P12V_B")
			(options
				(clearance outline)
				(anchor circle)
			)
			(primitives
				(gr_poly
					(pts
						(arc
							(start -0.1778 -0.2794)
							(mid -0.249642 -0.249642)
							(end -0.2794 -0.1778)
						)
						(arc
							(start -0.2794 0.1778)
							(mid -0.249642 0.249642)
							(end -0.1778 0.2794)
						)
						(arc
							(start 0.1778 0.2794)
							(mid 0.249642 0.249642)
							(end 0.2794 0.1778)
						)
						(arc
							(start 0.2794 -0.1778)
							(mid 0.249642 -0.249642)
							(end 0.1778 -0.2794)
						)
					)
					(width 0)
					(fill yes)
				)
			)
		)
		(pad "2" smd custom
			(at 0 0.4445 180)
			(size 0.1397 0.1397)
			(layers "F.Cu" "F.Mask" "F.Paste")
			(net "SW_HDD_R32")
			(options
				(clearance outline)
				(anchor circle)
			)
			(primitives
				(gr_poly
					(pts
						(arc
							(start -0.1778 -0.2794)
							(mid -0.249642 -0.249642)
							(end -0.2794 -0.1778)
						)
						(arc
							(start -0.2794 0.1778)
							(mid -0.249642 0.249642)
							(end -0.1778 0.2794)
						)
						(arc
							(start 0.1778 0.2794)
							(mid 0.249642 0.249642)
							(end 0.2794 0.1778)
						)
						(arc
							(start 0.2794 -0.1778)
							(mid 0.249642 -0.249642)
							(end 0.1778 -0.2794)
						)
					)
					(width 0)
					(fill yes)
				)
			)
		)
	)
)
